# S9S_MB_2U (Grand Teton) — schematic netlist excerpt (pin names and nets, part order shuffled) for the footprints in the layout excerpt that follows; sources: Cadence DE-HDL packaged netlist, KiCad conversion of 03242023_DA0F0TMBIJ0_F0T_Motherboard_J_brd_V01_OCP.brd

PC1198  Q_CAP  100NF 50V 10% X7R  pkg C0402  page 290 : A = SW_PVCCFA_EHV_FIVRA_CPU1_BOOT4_ ; B = SW_PVCCFA_EHV_FIVRA_CPU1_BOOTR4
R333  Q_RES  1K 1% EMPTY  pkg 0402LF  page 127 : A = P3V3_AUX ; B = PD_PIROM_CPU0_ADDR1

(kicad_pcb
	(version 20260206)
	(generator "pcbnew")
	(generator_version "10.0")
	(general
		(thickness 1.6)
		(legacy_teardrops no)
	)
	(paper "A4")
	(title_block
		(title "03242023_DA0F0TMBIJ0_F0T_Motherboard_J_brd_V01_OCP.brd")
		(comment 1 "Grand Teton / footprints 2753-2754 of 6105")
	)
	(layers
		(0 "F.Cu" signal "TOP")
		(4 "In1.Cu" signal "GND")
		(6 "In2.Cu" signal "IN1")
		(8 "In3.Cu" signal "GND1")
		(10 "In4.Cu" signal "IN2")
		(12 "In5.Cu" signal "GND2")
		(14 "In6.Cu" signal "IN3")
		(16 "In7.Cu" signal "GND3")
		(18 "In8.Cu" signal "VCC")
		(20 "In9.Cu" signal "VCC1")
		(22 "In10.Cu" signal "GND4")
		(24 "In11.Cu" signal "IN4")
		(26 "In12.Cu" signal "GND5")
		(28 "In13.Cu" signal "IN5")
		(30 "In14.Cu" signal "GND6")
		(32 "In15.Cu" signal "IN6")
		(34 "In16.Cu" signal "GND7")
		(2 "B.Cu" signal "BOTTOM")
		(9 "F.Adhes" user "F.Adhesive")
		(11 "B.Adhes" user "B.Adhesive")
		(13 "F.Paste" user "Package Geometry/Pastemask Top")
		(15 "B.Paste" user "Package Geometry/Pastemask Bottom")
		(5 "F.SilkS" user "Ref Des/Silkscreen Top")
		(7 "B.SilkS" user "Ref Des/Silkscreen Bottom")
		(1 "F.Mask" user "Board Geometry/Soldermask Top")
		(3 "B.Mask" user "Board Geometry/Soldermask Bottom")
		(17 "Dwgs.User" user "User.Drawings")
		(19 "Cmts.User" user "User.Comments")
		(21 "Eco1.User" user "User.Eco1")
		(23 "Eco2.User" user "User.Eco2")
		(25 "Edge.Cuts" user "Board Geometry/Outline")
		(27 "Margin" user)
		(31 "F.CrtYd" user "Package Geometry/Place Bound Top")
		(29 "B.CrtYd" user "Package Geometry/Place Bound Bottom")
		(35 "F.Fab" user "Ref Des/Assembly Top")
		(33 "B.Fab" user "Ref Des/Assembly Bottom")
	)
	(footprint ""
		(layer "F.Cu")
		(at 406.124664 -367.576862 180)
		(property "Reference" "R333"
			(at 0 0 180)
			(layer "F.SilkS")
			(hide yes)
			(effects
				(font
					(size 1.27 1.27)
				)
			)
		)
		(property "Value" ""
			(at 0 0 180)
			(layer "F.Fab")
			(effects
				(font
					(size 1.27 1.27)
				)
			)
		)
		(duplicate_pad_numbers_are_jumpers no)
		(fp_line
			(start 0.7874 0.4064)
			(end -0.7874 0.4064)
			(stroke
				(width 0.1524)
				(type default)
			)
			(layer "F.SilkS")
		)
		(fp_line
			(start 0.7874 -0.4064)
			(end 0.7874 0.4064)
			(stroke
				(width 0.1524)
				(type default)
			)
			(layer "F.SilkS")
		)
		(fp_line
			(start -0.7874 0.4064)
			(end -0.7874 -0.4064)
			(stroke
				(width 0.1524)
				(type default)
			)
			(layer "F.SilkS")
		)
		(fp_line
			(start -0.7874 -0.4064)
			(end 0.7874 -0.4064)
			(stroke
				(width 0.1524)
				(type default)
			)
			(layer "F.SilkS")
		)
		(fp_line
			(start 0.67945 0.3048)
			(end 0.120396 0.3048)
			(stroke
				(width 0.1)
				(type default)
			)
			(layer "F.Fab")
		)
		(fp_line
			(start 0.67945 -0.3048)
			(end 0.67945 0.3048)
			(stroke
				(width 0.1)
				(type default)
			)
			(layer "F.Fab")
		)
		(fp_line
			(start 0.12065 -0.2794)
			(end 0.12065 -0.3048)
			(stroke
				(width 0.1)
				(type default)
			)
			(layer "F.Fab")
		)
		(fp_line
			(start 0.12065 -0.3048)
			(end 0.67945 -0.3048)
			(stroke
				(width 0.1)
				(type default)
			)
			(layer "F.Fab")
		)
		(fp_line
			(start 0.120396 0.3048)
			(end 0.120396 0.2794)
			(stroke
				(width 0.1)
				(type default)
			)
			(layer "F.Fab")
		)
		(fp_line
			(start 0.120396 0.2794)
			(end -0.12065 0.2794)
			(stroke
				(width 0.1)
				(type default)
			)
			(layer "F.Fab")
		)
		(fp_line
			(start -0.12065 0.3048)
			(end -0.67945 0.3048)
			(stroke
				(width 0.1)
				(type default)
			)
			(layer "F.Fab")
		)
		(fp_line
			(start -0.12065 0.2794)
			(end -0.12065 0.3048)
			(stroke
				(width 0.1)
				(type default)
			)
			(layer "F.Fab")
		)
		(fp_line
			(start -0.12065 -0.2794)
			(end 0.12065 -0.2794)
			(stroke
				(width 0.1)
				(type default)
			)
			(layer "F.Fab")
		)
		(fp_line
			(start -0.12065 -0.305054)
			(end -0.12065 -0.2794)
			(stroke
				(width 0.1)
				(type default)
			)
			(layer "F.Fab")
		)
		(fp_line
			(start -0.67945 0.3048)
			(end -0.67945 -0.305054)
			(stroke
				(width 0.1)
				(type default)
			)
			(layer "F.Fab")
		)
		(fp_line
			(start -0.67945 -0.305054)
			(end -0.12065 -0.305054)
			(stroke
				(width 0.1)
				(type default)
			)
			(layer "F.Fab")
		)
		(pad "1" smd circle
			(at -0.40005 0 180)
			(size 0 0)
			(layers "F.Cu" "F.Mask" "F.Paste")
			(net "P3V3_AUX")
		)
		(pad "2" smd circle
			(at 0.40005 0 180)
			(size 0 0)
			(layers "F.Cu" "F.Mask" "F.Paste")
			(net "PD_PIROM_CPU0_ADDR1")
		)
	)
	(footprint ""
		(layer "F.Cu")
		(at 43.350942 -358.38003 -90)
		(property "Reference" "PC1198"
			(at 0 0 270)
			(layer "F.SilkS")
			(hide yes)
			(effects
				(font
					(size 1.27 1.27)
				)
			)
		)
		(property "Value" ""
			(at 0 0 270)
			(layer "F.Fab")
			(effects
				(font
					(size 1.27 1.27)
				)
			)
		)
		(duplicate_pad_numbers_are_jumpers no)
		(fp_line
			(start -0.7874 0.4064)
			(end -0.7874 -0.4064)
			(stroke
				(width 0.1524)
				(type default)
			)
			(layer "F.SilkS")
		)
		(fp_line
			(start 0.7874 0.4064)
			(end -0.7874 0.4064)
			(stroke
				(width 0.1524)
				(type default)
			)
			(layer "F.SilkS")
		)
		(fp_line
			(start -0.7874 -0.4064)
			(end 0.7874 -0.4064)
			(stroke
				(width 0.1524)
				(type default)
			)
			(layer "F.SilkS")
		)
		(fp_line
			(start 0.7874 -0.4064)
			(end 0.7874 0.4064)
			(stroke
				(width 0.1524)
				(type default)
			)
			(layer "F.SilkS")
		)
		(fp_line
			(start -0.67945 0.3048)
			(end -0.67945 -0.305054)
			(stroke
				(width 0.1)
				(type default)
			)
			(layer "F.Fab")
		)
		(fp_line
			(start -0.12065 0.3048)
			(end -0.67945 0.3048)
			(stroke
				(width 0.1)
				(type default)
			)
			(layer "F.Fab")
		)
		(fp_line
			(start 0.120396 0.3048)
			(end 0.120396 0.2794)
			(stroke
				(width 0.1)
				(type default)
			)
			(layer "F.Fab")
		)
		(fp_line
			(start 0.67945 0.3048)
			(end 0.120396 0.3048)
			(stroke
				(width 0.1)
				(type default)
			)
			(layer "F.Fab")
		)
		(fp_line
			(start -0.12065 0.2794)
			(end -0.12065 0.3048)
			(stroke
				(width 0.1)
				(type default)
			)
			(layer "F.Fab")
		)
		(fp_line
			(start 0.120396 0.2794)
			(end -0.12065 0.2794)
			(stroke
				(width 0.1)
				(type default)
			)
			(layer "F.Fab")
		)
		(fp_line
			(start -0.12065 -0.2794)
			(end 0.12065 -0.2794)
			(stroke
				(width 0.1)
				(type default)
			)
			(layer "F.Fab")
		)
		(fp_line
			(start 0.12065 -0.2794)
			(end 0.12065 -0.3048)
			(stroke
				(width 0.1)
				(type default)
			)
			(layer "F.Fab")
		)
		(fp_line
			(start 0.12065 -0.3048)
			(end 0.67945 -0.3048)
			(stroke
				(width 0.1)
				(type default)
			)
			(layer "F.Fab")
		)
		(fp_line
			(start 0.67945 -0.3048)
			(end 0.67945 0.3048)
			(stroke
				(width 0.1)
				(type default)
			)
			(layer "F.Fab")
		)
		(fp_line
			(start -0.67945 -0.305054)
			(end -0.12065 -0.305054)
			(stroke
				(width 0.1)
				(type default)
			)
			(layer "F.Fab")
		)
		(fp_line
			(start -0.12065 -0.305054)
			(end -0.12065 -0.2794)
			(stroke
				(width 0.1)
				(type default)
			)
			(layer "F.Fab")
		)
		(pad "1" smd circle
			(at -0.40005 0 270)
			(size 0 0)
			(layers "F.Cu" "F.Mask" "F.Paste")
			(net "SW_PVCCFA_EHV_FIVRA_CPU1_BOOT4_")
		)
		(pad "2" smd circle
			(at 0.40005 0 270)
			(size 0 0)
			(layers "F.Cu" "F.Mask" "F.Paste")
			(net "SW_PVCCFA_EHV_FIVRA_CPU1_BOOTR4")
		)
	)
)
